# S9S_MB_2U (Grand Teton) — schematic netlist excerpt (pin names and nets, part order shuffled) for the footprints in the layout excerpt that follows; sources: Cadence DE-HDL packaged netlist, KiCad conversion of 03242023_DA0F0TMBIJ0_F0T_Motherboard_J_brd_V01_OCP.brd

C406  Q_CAP  22UF 4V 20% X6S  pkg C0402  page 74 : A = PVCCFA_EHV_FIVRA_CPU0 ; B = GND
PC1652  Q_CAP  100NF 50V 10% X7R  pkg C0402  page 267 : A = P12V_AUX ; B = GND

(kicad_pcb
	(version 20260206)
	(generator "pcbnew")
	(generator_version "10.0")
	(general
		(thickness 1.6)
		(legacy_teardrops no)
	)
	(paper "A4")
	(title_block
		(title "03242023_DA0F0TMBIJ0_F0T_Motherboard_J_brd_V01_OCP.brd")
		(comment 1 "Grand Teton / footprints 3776-3777 of 6105")
	)
	(layers
		(0 "F.Cu" signal "TOP")
		(4 "In1.Cu" signal "GND")
		(6 "In2.Cu" signal "IN1")
		(8 "In3.Cu" signal "GND1")
		(10 "In4.Cu" signal "IN2")
		(12 "In5.Cu" signal "GND2")
		(14 "In6.Cu" signal "IN3")
		(16 "In7.Cu" signal "GND3")
		(18 "In8.Cu" signal "VCC")
		(20 "In9.Cu" signal "VCC1")
		(22 "In10.Cu" signal "GND4")
		(24 "In11.Cu" signal "IN4")
		(26 "In12.Cu" signal "GND5")
		(28 "In13.Cu" signal "IN5")
		(30 "In14.Cu" signal "GND6")
		(32 "In15.Cu" signal "IN6")
		(34 "In16.Cu" signal "GND7")
		(2 "B.Cu" signal "BOTTOM")
		(9 "F.Adhes" user "F.Adhesive")
		(11 "B.Adhes" user "B.Adhesive")
		(13 "F.Paste" user "Package Geometry/Pastemask Top")
		(15 "B.Paste" user "Package Geometry/Pastemask Bottom")
		(5 "F.SilkS" user "Ref Des/Silkscreen Top")
		(7 "B.SilkS" user "Ref Des/Silkscreen Bottom")
		(1 "F.Mask" user "Board Geometry/Soldermask Top")
		(3 "B.Mask" user "Board Geometry/Soldermask Bottom")
		(17 "Dwgs.User" user "User.Drawings")
		(19 "Cmts.User" user "User.Comments")
		(21 "Eco1.User" user "User.Eco1")
		(23 "Eco2.User" user "User.Eco2")
		(25 "Edge.Cuts" user "Board Geometry/Outline")
		(27 "Margin" user)
		(31 "F.CrtYd" user "Package Geometry/Place Bound Top")
		(29 "B.CrtYd" user "Package Geometry/Place Bound Bottom")
		(35 "F.Fab" user "Ref Des/Assembly Top")
		(33 "B.Fab" user "Ref Des/Assembly Bottom")
	)
	(footprint ""
		(layer "F.Cu")
		(at 352.264726 -260.364986 -90)
		(property "Reference" "C406"
			(at 0 0 270)
			(layer "F.SilkS")
			(hide yes)
			(effects
				(font
					(size 1.27 1.27)
				)
			)
		)
		(property "Value" ""
			(at 0 0 270)
			(layer "F.Fab")
			(effects
				(font
					(size 1.27 1.27)
				)
			)
		)
		(duplicate_pad_numbers_are_jumpers no)
		(fp_line
			(start -0.7874 0.4064)
			(end -0.7874 -0.4064)
			(stroke
				(width 0.1524)
				(type default)
			)
			(layer "F.SilkS")
		)
		(fp_line
			(start 0.7874 0.4064)
			(end -0.7874 0.4064)
			(stroke
				(width 0.1524)
				(type default)
			)
			(layer "F.SilkS")
		)
		(fp_line
			(start -0.7874 -0.4064)
			(end 0.7874 -0.4064)
			(stroke
				(width 0.1524)
				(type default)
			)
			(layer "F.SilkS")
		)
		(fp_line
			(start 0.7874 -0.4064)
			(end 0.7874 0.4064)
			(stroke
				(width 0.1524)
				(type default)
			)
			(layer "F.SilkS")
		)
		(fp_line
			(start -0.67945 0.3048)
			(end -0.67945 -0.305054)
			(stroke
				(width 0.1)
				(type default)
			)
			(layer "F.Fab")
		)
		(fp_line
			(start -0.12065 0.3048)
			(end -0.67945 0.3048)
			(stroke
				(width 0.1)
				(type default)
			)
			(layer "F.Fab")
		)
		(fp_line
			(start 0.120396 0.3048)
			(end 0.120396 0.2794)
			(stroke
				(width 0.1)
				(type default)
			)
			(layer "F.Fab")
		)
		(fp_line
			(start 0.67945 0.3048)
			(end 0.120396 0.3048)
			(stroke
				(width 0.1)
				(type default)
			)
			(layer "F.Fab")
		)
		(fp_line
			(start -0.12065 0.2794)
			(end -0.12065 0.3048)
			(stroke
				(width 0.1)
				(type default)
			)
			(layer "F.Fab")
		)
		(fp_line
			(start 0.120396 0.2794)
			(end -0.12065 0.2794)
			(stroke
				(width 0.1)
				(type default)
			)
			(layer "F.Fab")
		)
		(fp_line
			(start -0.12065 -0.2794)
			(end 0.12065 -0.2794)
			(stroke
				(width 0.1)
				(type default)
			)
			(layer "F.Fab")
		)
		(fp_line
			(start 0.12065 -0.2794)
			(end 0.12065 -0.3048)
			(stroke
				(width 0.1)
				(type default)
			)
			(layer "F.Fab")
		)
		(fp_line
			(start 0.12065 -0.3048)
			(end 0.67945 -0.3048)
			(stroke
				(width 0.1)
				(type default)
			)
			(layer "F.Fab")
		)
		(fp_line
			(start 0.67945 -0.3048)
			(end 0.67945 0.3048)
			(stroke
				(width 0.1)
				(type default)
			)
			(layer "F.Fab")
		)
		(fp_line
			(start -0.67945 -0.305054)
			(end -0.12065 -0.305054)
			(stroke
				(width 0.1)
				(type default)
			)
			(layer "F.Fab")
		)
		(fp_line
			(start -0.12065 -0.305054)
			(end -0.12065 -0.2794)
			(stroke
				(width 0.1)
				(type default)
			)
			(layer "F.Fab")
		)
		(pad "1" smd circle
			(at -0.40005 0 270)
			(size 0 0)
			(layers "F.Cu" "F.Mask" "F.Paste")
			(net "PVCCFA_EHV_FIVRA_CPU0")
		)
		(pad "2" smd circle
			(at 0.40005 0 270)
			(size 0 0)
			(layers "F.Cu" "F.Mask" "F.Paste")
			(net "GND")
		)
	)
	(footprint ""
		(layer "F.Cu")
		(at 345.002358 -354.98913 -90)
		(property "Reference" "PC1652"
			(at 0 0 270)
			(layer "F.SilkS")
			(hide yes)
			(effects
				(font
					(size 1.27 1.27)
				)
			)
		)
		(property "Value" ""
			(at 0 0 270)
			(layer "F.Fab")
			(effects
				(font
					(size 1.27 1.27)
				)
			)
		)
		(duplicate_pad_numbers_are_jumpers no)
		(fp_line
			(start -0.7874 0.4064)
			(end -0.7874 -0.4064)
			(stroke
				(width 0.1524)
				(type default)
			)
			(layer "F.SilkS")
		)
		(fp_line
			(start 0.7874 0.4064)
			(end -0.7874 0.4064)
			(stroke
				(width 0.1524)
				(type default)
			)
			(layer "F.SilkS")
		)
		(fp_line
			(start -0.7874 -0.4064)
			(end 0.7874 -0.4064)
			(stroke
				(width 0.1524)
				(type default)
			)
			(layer "F.SilkS")
		)
		(fp_line
			(start 0.7874 -0.4064)
			(end 0.7874 0.4064)
			(stroke
				(width 0.1524)
				(type default)
			)
			(layer "F.SilkS")
		)
		(fp_line
			(start -0.67945 0.3048)
			(end -0.67945 -0.305054)
			(stroke
				(width 0.1)
				(type default)
			)
			(layer "F.Fab")
		)
		(fp_line
			(start -0.12065 0.3048)
			(end -0.67945 0.3048)
			(stroke
				(width 0.1)
				(type default)
			)
			(layer "F.Fab")
		)
		(fp_line
			(start 0.120396 0.3048)
			(end 0.120396 0.2794)
			(stroke
				(width 0.1)
				(type default)
			)
			(layer "F.Fab")
		)
		(fp_line
			(start 0.67945 0.3048)
			(end 0.120396 0.3048)
			(stroke
				(width 0.1)
				(type default)
			)
			(layer "F.Fab")
		)
		(fp_line
			(start -0.12065 0.2794)
			(end -0.12065 0.3048)
			(stroke
				(width 0.1)
				(type default)
			)
			(layer "F.Fab")
		)
		(fp_line
			(start 0.120396 0.2794)
			(end -0.12065 0.2794)
			(stroke
				(width 0.1)
				(type default)
			)
			(layer "F.Fab")
		)
		(fp_line
			(start -0.12065 -0.2794)
			(end 0.12065 -0.2794)
			(stroke
				(width 0.1)
				(type default)
			)
			(layer "F.Fab")
		)
		(fp_line
			(start 0.12065 -0.2794)
			(end 0.12065 -0.3048)
			(stroke
				(width 0.1)
				(type default)
			)
			(layer "F.Fab")
		)
		(fp_line
			(start 0.12065 -0.3048)
			(end 0.67945 -0.3048)
			(stroke
				(width 0.1)
				(type default)
			)
			(layer "F.Fab")
		)
		(fp_line
			(start 0.67945 -0.3048)
			(end 0.67945 0.3048)
			(stroke
				(width 0.1)
				(type default)
			)
			(layer "F.Fab")
		)
		(fp_line
			(start -0.67945 -0.305054)
			(end -0.12065 -0.305054)
			(stroke
				(width 0.1)
				(type default)
			)
			(layer "F.Fab")
		)
		(fp_line
			(start -0.12065 -0.305054)
			(end -0.12065 -0.2794)
			(stroke
				(width 0.1)
				(type default)
			)
			(layer "F.Fab")
		)
		(pad "1" smd circle
			(at -0.40005 0 270)
			(size 0 0)
			(layers "F.Cu" "F.Mask" "F.Paste")
			(net "P12V_AUX")
		)
		(pad "2" smd circle
			(at 0.40005 0 270)
			(size 0 0)
			(layers "F.Cu" "F.Mask" "F.Paste")
			(net "GND")
		)
	)
)
